(kicad_pcb
	(version 20260206)
	(generator "pcbnew")
	(generator_version "10.0")
	(general
		(thickness 1.6)
		(legacy_teardrops no)
	)
	(paper "A4")
	(title_block
		(title "04192023_DAF0TMB3IC0_F0TG_MB_C_brd_V02_OCP.brd")
		(comment 1 "Grand Teton / footprints 1888-1893 of 8354")
	)
	(layers
		(0 "F.Cu" signal "TOP")
		(4 "In1.Cu" signal "GND")
		(6 "In2.Cu" signal "IN1")
		(8 "In3.Cu" signal "GND1")
		(10 "In4.Cu" signal "IN2")
		(12 "In5.Cu" signal "GND2")
		(14 "In6.Cu" signal "IN3")
		(16 "In7.Cu" signal "GND3")
		(18 "In8.Cu" signal "VCC")
		(20 "In9.Cu" signal "VCC1")
		(22 "In10.Cu" signal "GND4")
		(24 "In11.Cu" signal "IN4")
		(26 "In12.Cu" signal "GND5")
		(28 "In13.Cu" signal "IN5")
		(30 "In14.Cu" signal "GND6")
		(32 "In15.Cu" signal "IN6")
		(34 "In16.Cu" signal "GND7")
		(2 "B.Cu" signal "BOTTOM")
		(9 "F.Adhes" user "F.Adhesive")
		(11 "B.Adhes" user "B.Adhesive")
		(13 "F.Paste" user "Package Geometry/Pastemask Top")
		(15 "B.Paste" user "Package Geometry/Pastemask Bottom")
		(5 "F.SilkS" user "Ref Des/Silkscreen Top")
		(7 "B.SilkS" user "Ref Des/Silkscreen Bottom")
		(1 "F.Mask" user "Board Geometry/Soldermask Top")
		(3 "B.Mask" user "Board Geometry/Soldermask Bottom")
		(17 "Dwgs.User" user "User.Drawings")
		(19 "Cmts.User" user "User.Comments")
		(21 "Eco1.User" user "User.Eco1")
		(23 "Eco2.User" user "User.Eco2")
		(25 "Edge.Cuts" user "Board Geometry/Outline")
		(27 "Margin" user)
		(31 "F.CrtYd" user "Package Geometry/Place Bound Top")
		(29 "B.CrtYd" user "Package Geometry/Place Bound Bottom")
		(35 "F.Fab" user "Ref Des/Assembly Top")
		(33 "B.Fab" user "Ref Des/Assembly Bottom")
	)
	(footprint ""
		(layer "F.Cu")
		(at 281.621738 -388.71652 90)
		(property "Reference" "R6230"
			(at 0 0 90)
			(layer "F.SilkS")
			(hide yes)
			(effects
				(font
					(size 1.27 1.27)
				)
			)
		)
		(property "Value" ""
			(at 0 0 90)
			(layer "F.Fab")
			(effects
				(font
					(size 1.27 1.27)
				)
			)
		)
		(duplicate_pad_numbers_are_jumpers no)
		(fp_line
			(start 0.7874 -0.4064)
			(end 0.7874 0.4064)
			(stroke
				(width 0.1524)
				(type default)
			)
			(layer "F.SilkS")
		)
		(fp_line
			(start -0.7874 -0.4064)
			(end 0.7874 -0.4064)
			(stroke
				(width 0.1524)
				(type default)
			)
			(layer "F.SilkS")
		)
		(fp_line
			(start 0.7874 0.4064)
			(end -0.7874 0.4064)
			(stroke
				(width 0.1524)
				(type default)
			)
			(layer "F.SilkS")
		)
		(fp_line
			(start -0.7874 0.4064)
			(end -0.7874 -0.4064)
			(stroke
				(width 0.1524)
				(type default)
			)
			(layer "F.SilkS")
		)
		(fp_line
			(start -0.12065 -0.305054)
			(end -0.12065 -0.2794)
			(stroke
				(width 0.1)
				(type default)
			)
			(layer "F.Fab")
		)
		(fp_line
			(start -0.67945 -0.305054)
			(end -0.12065 -0.305054)
			(stroke
				(width 0.1)
				(type default)
			)
			(layer "F.Fab")
		)
		(fp_line
			(start 0.67945 -0.3048)
			(end 0.67945 0.3048)
			(stroke
				(width 0.1)
				(type default)
			)
			(layer "F.Fab")
		)
		(fp_line
			(start 0.12065 -0.3048)
			(end 0.67945 -0.3048)
			(stroke
				(width 0.1)
				(type default)
			)
			(layer "F.Fab")
		)
		(fp_line
			(start 0.12065 -0.2794)
			(end 0.12065 -0.3048)
			(stroke
				(width 0.1)
				(type default)
			)
			(layer "F.Fab")
		)
		(fp_line
			(start -0.12065 -0.2794)
			(end 0.12065 -0.2794)
			(stroke
				(width 0.1)
				(type default)
			)
			(layer "F.Fab")
		)
		(fp_line
			(start 0.120396 0.2794)
			(end -0.12065 0.2794)
			(stroke
				(width 0.1)
				(type default)
			)
			(layer "F.Fab")
		)
		(fp_line
			(start -0.12065 0.2794)
			(end -0.12065 0.3048)
			(stroke
				(width 0.1)
				(type default)
			)
			(layer "F.Fab")
		)
		(fp_line
			(start 0.67945 0.3048)
			(end 0.120396 0.3048)
			(stroke
				(width 0.1)
				(type default)
			)
			(layer "F.Fab")
		)
		(fp_line
			(start 0.120396 0.3048)
			(end 0.120396 0.2794)
			(stroke
				(width 0.1)
				(type default)
			)
			(layer "F.Fab")
		)
		(fp_line
			(start -0.12065 0.3048)
			(end -0.67945 0.3048)
			(stroke
				(width 0.1)
				(type default)
			)
			(layer "F.Fab")
		)
		(fp_line
			(start -0.67945 0.3048)
			(end -0.67945 -0.305054)
			(stroke
				(width 0.1)
				(type default)
			)
			(layer "F.Fab")
		)
		(pad "1" smd circle
			(at -0.40005 0 90)
			(size 0 0)
			(layers "F.Cu" "F.Mask" "F.Paste")
			(net "P3V3_AUX")
		)
		(pad "2" smd circle
			(at 0.40005 0 90)
			(size 0 0)
			(layers "F.Cu" "F.Mask" "F.Paste")
			(net "SMB_P12V_HSC_SDA")
		)
	)
	(footprint ""
		(layer "F.Cu")
		(at 347.972126 -336.930238 180)
		(property "Reference" "PC154"
			(at 0 0 180)
			(layer "F.SilkS")
			(hide yes)
			(effects
				(font
					(size 1.27 1.27)
				)
			)
		)
		(property "Value" ""
			(at 0 0 180)
			(layer "F.Fab")
			(effects
				(font
					(size 1.27 1.27)
				)
			)
		)
		(duplicate_pad_numbers_are_jumpers no)
		(fp_line
			(start 0.7874 0.4064)
			(end -0.7874 0.4064)
			(stroke
				(width 0.1524)
				(type default)
			)
			(layer "F.SilkS")
		)
		(fp_line
			(start 0.7874 -0.4064)
			(end 0.7874 0.4064)
			(stroke
				(width 0.1524)
				(type default)
			)
			(layer "F.SilkS")
		)
		(fp_line
			(start -0.7874 0.4064)
			(end -0.7874 -0.4064)
			(stroke
				(width 0.1524)
				(type default)
			)
			(layer "F.SilkS")
		)
		(fp_line
			(start -0.7874 -0.4064)
			(end 0.7874 -0.4064)
			(stroke
				(width 0.1524)
				(type default)
			)
			(layer "F.SilkS")
		)
		(fp_line
			(start 0.67945 0.3048)
			(end 0.120396 0.3048)
			(stroke
				(width 0.1)
				(type default)
			)
			(layer "F.Fab")
		)
		(fp_line
			(start 0.67945 -0.3048)
			(end 0.67945 0.3048)
			(stroke
				(width 0.1)
				(type default)
			)
			(layer "F.Fab")
		)
		(fp_line
			(start 0.12065 -0.2794)
			(end 0.12065 -0.3048)
			(stroke
				(width 0.1)
				(type default)
			)
			(layer "F.Fab")
		)
		(fp_line
			(start 0.12065 -0.3048)
			(end 0.67945 -0.3048)
			(stroke
				(width 0.1)
				(type default)
			)
			(layer "F.Fab")
		)
		(fp_line
			(start 0.120396 0.3048)
			(end 0.120396 0.2794)
			(stroke
				(width 0.1)
				(type default)
			)
			(layer "F.Fab")
		)
		(fp_line
			(start 0.120396 0.2794)
			(end -0.12065 0.2794)
			(stroke
				(width 0.1)
				(type default)
			)
			(layer "F.Fab")
		)
		(fp_line
			(start -0.12065 0.3048)
			(end -0.67945 0.3048)
			(stroke
				(width 0.1)
				(type default)
			)
			(layer "F.Fab")
		)
		(fp_line
			(start -0.12065 0.2794)
			(end -0.12065 0.3048)
			(stroke
				(width 0.1)
				(type default)
			)
			(layer "F.Fab")
		)
		(fp_line
			(start -0.12065 -0.2794)
			(end 0.12065 -0.2794)
			(stroke
				(width 0.1)
				(type default)
			)
			(layer "F.Fab")
		)
		(fp_line
			(start -0.12065 -0.305054)
			(end -0.12065 -0.2794)
			(stroke
				(width 0.1)
				(type default)
			)
			(layer "F.Fab")
		)
		(fp_line
			(start -0.67945 0.3048)
			(end -0.67945 -0.305054)
			(stroke
				(width 0.1)
				(type default)
			)
			(layer "F.Fab")
		)
		(fp_line
			(start -0.67945 -0.305054)
			(end -0.12065 -0.305054)
			(stroke
				(width 0.1)
				(type default)
			)
			(layer "F.Fab")
		)
		(pad "1" smd circle
			(at -0.40005 0 180)
			(size 0 0)
			(layers "F.Cu" "F.Mask" "F.Paste")
			(net "SW_PVDDCR_CPU1_P0_SW6")
		)
		(pad "2" smd circle
			(at 0.40005 0 180)
			(size 0 0)
			(layers "F.Cu" "F.Mask" "F.Paste")
			(net "SW_PVDDCR_CPU1_P0_SW6_RC")
		)
	)
	(footprint ""
		(layer "F.Cu")
		(at 98.845878 -143.74241 180)
		(property "Reference" "PR4"
			(at 0 0 180)
			(layer "F.SilkS")
			(hide yes)
			(effects
				(font
					(size 1.27 1.27)
				)
			)
		)
		(property "Value" ""
			(at 0 0 180)
			(layer "F.Fab")
			(effects
				(font
					(size 1.27 1.27)
				)
			)
		)
		(duplicate_pad_numbers_are_jumpers no)
		(fp_line
			(start 0.7874 0.4064)
			(end -0.7874 0.4064)
			(stroke
				(width 0.1524)
				(type default)
			)
			(layer "F.SilkS")
		)
		(fp_line
			(start 0.7874 -0.4064)
			(end 0.7874 0.4064)
			(stroke
				(width 0.1524)
				(type default)
			)
			(layer "F.SilkS")
		)
		(fp_line
			(start -0.7874 0.4064)
			(end -0.7874 -0.4064)
			(stroke
				(width 0.1524)
				(type default)
			)
			(layer "F.SilkS")
		)
		(fp_line
			(start -0.7874 -0.4064)
			(end 0.7874 -0.4064)
			(stroke
				(width 0.1524)
				(type default)
			)
			(layer "F.SilkS")
		)
		(fp_line
			(start 0.67945 0.3048)
			(end 0.120396 0.3048)
			(stroke
				(width 0.1)
				(type default)
			)
			(layer "F.Fab")
		)
		(fp_line
			(start 0.67945 -0.3048)
			(end 0.67945 0.3048)
			(stroke
				(width 0.1)
				(type default)
			)
			(layer "F.Fab")
		)
		(fp_line
			(start 0.12065 -0.2794)
			(end 0.12065 -0.3048)
			(stroke
				(width 0.1)
				(type default)
			)
			(layer "F.Fab")
		)
		(fp_line
			(start 0.12065 -0.3048)
			(end 0.67945 -0.3048)
			(stroke
				(width 0.1)
				(type default)
			)
			(layer "F.Fab")
		)
		(fp_line
			(start 0.120396 0.3048)
			(end 0.120396 0.2794)
			(stroke
				(width 0.1)
				(type default)
			)
			(layer "F.Fab")
		)
		(fp_line
			(start 0.120396 0.2794)
			(end -0.12065 0.2794)
			(stroke
				(width 0.1)
				(type default)
			)
			(layer "F.Fab")
		)
		(fp_line
			(start -0.12065 0.3048)
			(end -0.67945 0.3048)
			(stroke
				(width 0.1)
				(type default)
			)
			(layer "F.Fab")
		)
		(fp_line
			(start -0.12065 0.2794)
			(end -0.12065 0.3048)
			(stroke
				(width 0.1)
				(type default)
			)
			(layer "F.Fab")
		)
		(fp_line
			(start -0.12065 -0.2794)
			(end 0.12065 -0.2794)
			(stroke
				(width 0.1)
				(type default)
			)
			(layer "F.Fab")
		)
		(fp_line
			(start -0.12065 -0.305054)
			(end -0.12065 -0.2794)
			(stroke
				(width 0.1)
				(type default)
			)
			(layer "F.Fab")
		)
		(fp_line
			(start -0.67945 0.3048)
			(end -0.67945 -0.305054)
			(stroke
				(width 0.1)
				(type default)
			)
			(layer "F.Fab")
		)
		(fp_line
			(start -0.67945 -0.305054)
			(end -0.12065 -0.305054)
			(stroke
				(width 0.1)
				(type default)
			)
			(layer "F.Fab")
		)
		(pad "1" smd circle
			(at -0.40005 0 180)
			(size 0 0)
			(layers "F.Cu" "F.Mask" "F.Paste")
			(net "PVDDCR_CPU0_P1_VMON")
		)
		(pad "2" smd circle
			(at 0.40005 0 180)
			(size 0 0)
			(layers "F.Cu" "F.Mask" "F.Paste")
			(net "GND")
		)
	)
	(footprint ""
		(layer "F.Cu")
		(at 373.931942 -416.899344 -90)
		(property "Reference" "C6568"
			(at 0 0 270)
			(layer "F.SilkS")
			(hide yes)
			(effects
				(font
					(size 1.27 1.27)
				)
			)
		)
		(property "Value" ""
			(at 0 0 270)
			(layer "F.Fab")
			(effects
				(font
					(size 1.27 1.27)
				)
			)
		)
		(duplicate_pad_numbers_are_jumpers no)
		(fp_line
			(start -0.299974 0.150114)
			(end -0.299974 -0.150114)
			(stroke
				(width 0.1)
				(type default)
			)
			(layer "F.Fab")
		)
		(fp_line
			(start 0.299974 0.150114)
			(end -0.299974 0.150114)
			(stroke
				(width 0.1)
				(type default)
			)
			(layer "F.Fab")
		)
		(fp_line
			(start -0.299974 -0.150114)
			(end 0.299974 -0.150114)
			(stroke
				(width 0.1)
				(type default)
			)
			(layer "F.Fab")
		)
		(fp_line
			(start 0.299974 -0.150114)
			(end 0.299974 0.150114)
			(stroke
				(width 0.1)
				(type default)
			)
			(layer "F.Fab")
		)
		(pad "1" smd rect
			(at -0.2667 0 270)
			(size 0.3048 0.381)
			(layers "F.Cu" "F.Mask" "F.Paste")
			(net "P5E_CPU0_P2_TX_BUF_C_DN<1>")
		)
		(pad "2" smd rect
			(at 0.2667 0 270)
			(size 0.3048 0.381)
			(layers "F.Cu" "F.Mask" "F.Paste")
			(net "P5E_CPU0_P2_TX_BUF_DN<1>")
		)
	)
	(footprint ""
		(layer "F.Cu")
		(at 323.018404 -337.653376 90)
		(property "Reference" "PC80"
			(at 0 0 90)
			(layer "F.SilkS")
			(hide yes)
			(effects
				(font
					(size 1.27 1.27)
				)
			)
		)
		(property "Value" ""
			(at 0 0 90)
			(layer "F.Fab")
			(effects
				(font
					(size 1.27 1.27)
				)
			)
		)
		(duplicate_pad_numbers_are_jumpers no)
		(fp_line
			(start 0.7874 -0.4064)
			(end 0.7874 0.4064)
			(stroke
				(width 0.1524)
				(type default)
			)
			(layer "F.SilkS")
		)
		(fp_line
			(start -0.7874 -0.4064)
			(end 0.7874 -0.4064)
			(stroke
				(width 0.1524)
				(type default)
			)
			(layer "F.SilkS")
		)
		(fp_line
			(start 0.7874 0.4064)
			(end 0.039624 0.4064)
			(stroke
				(width 0.1524)
				(type default)
			)
			(layer "F.SilkS")
		)
		(fp_line
			(start -0.7874 0.4064)
			(end -0.7874 -0.4064)
			(stroke
				(width 0.1524)
				(type default)
			)
			(layer "F.SilkS")
		)
		(fp_line
			(start -0.12065 -0.305054)
			(end -0.12065 -0.2794)
			(stroke
				(width 0.1)
				(type default)
			)
			(layer "F.Fab")
		)
		(fp_line
			(start -0.67945 -0.305054)
			(end -0.12065 -0.305054)
			(stroke
				(width 0.1)
				(type default)
			)
			(layer "F.Fab")
		)
		(fp_line
			(start 0.67945 -0.3048)
			(end 0.67945 0.3048)
			(stroke
				(width 0.1)
				(type default)
			)
			(layer "F.Fab")
		)
		(fp_line
			(start 0.12065 -0.3048)
			(end 0.67945 -0.3048)
			(stroke
				(width 0.1)
				(type default)
			)
			(layer "F.Fab")
		)
		(fp_line
			(start 0.12065 -0.2794)
			(end 0.12065 -0.3048)
			(stroke
				(width 0.1)
				(type default)
			)
			(layer "F.Fab")
		)
		(fp_line
			(start -0.12065 -0.2794)
			(end 0.12065 -0.2794)
			(stroke
				(width 0.1)
				(type default)
			)
			(layer "F.Fab")
		)
		(fp_line
			(start 0.120396 0.2794)
			(end -0.12065 0.2794)
			(stroke
				(width 0.1)
				(type default)
			)
			(layer "F.Fab")
		)
		(fp_line
			(start -0.12065 0.2794)
			(end -0.12065 0.3048)
			(stroke
				(width 0.1)
				(type default)
			)
			(layer "F.Fab")
		)
		(fp_line
			(start 0.67945 0.3048)
			(end 0.120396 0.3048)
			(stroke
				(width 0.1)
				(type default)
			)
			(layer "F.Fab")
		)
		(fp_line
			(start 0.120396 0.3048)
			(end 0.120396 0.2794)
			(stroke
				(width 0.1)
				(type default)
			)
			(layer "F.Fab")
		)
		(fp_line
			(start -0.12065 0.3048)
			(end -0.67945 0.3048)
			(stroke
				(width 0.1)
				(type default)
			)
			(layer "F.Fab")
		)
		(fp_line
			(start -0.67945 0.3048)
			(end -0.67945 -0.305054)
			(stroke
				(width 0.1)
				(type default)
			)
			(layer "F.Fab")
		)
		(pad "1" smd circle
			(at -0.40005 0 90)
			(size 0 0)
			(layers "F.Cu" "F.Mask" "F.Paste")
			(net "PVDDCR_CPU1_P0_VCC2")
		)
		(pad "2" smd circle
			(at 0.40005 0 90)
			(size 0 0)
			(layers "F.Cu" "F.Mask" "F.Paste")
			(net "GND")
		)
	)
	(footprint ""
		(layer "F.Cu")
		(at 107.677204 -261.748016 -90)
		(property "Reference" "C2262"
			(at 0 0 270)
			(layer "F.SilkS")
			(hide yes)
			(effects
				(font
					(size 1.27 1.27)
				)
			)
		)
		(property "Value" ""
			(at 0 0 270)
			(layer "F.Fab")
			(effects
				(font
					(size 1.27 1.27)
				)
			)
		)
		(duplicate_pad_numbers_are_jumpers no)
		(fp_line
			(start -0.7874 0.4064)
			(end -0.7874 -0.4064)
			(stroke
				(width 0.1524)
				(type default)
			)
			(layer "F.SilkS")
		)
		(fp_line
			(start 0.7874 0.4064)
			(end -0.7874 0.4064)
			(stroke
				(width 0.1524)
				(type default)
			)
			(layer "F.SilkS")
		)
		(fp_line
			(start -0.7874 -0.4064)
			(end 0.7874 -0.4064)
			(stroke
				(width 0.1524)
				(type default)
			)
			(layer "F.SilkS")
		)
		(fp_line
			(start 0.7874 -0.4064)
			(end 0.7874 0.4064)
			(stroke
				(width 0.1524)
				(type default)
			)
			(layer "F.SilkS")
		)
		(fp_line
			(start -0.67945 0.3048)
			(end -0.67945 -0.305054)
			(stroke
				(width 0.1)
				(type default)
			)
			(layer "F.Fab")
		)
		(fp_line
			(start -0.12065 0.3048)
			(end -0.67945 0.3048)
			(stroke
				(width 0.1)
				(type default)
			)
			(layer "F.Fab")
		)
		(fp_line
			(start 0.120396 0.3048)
			(end 0.120396 0.2794)
			(stroke
				(width 0.1)
				(type default)
			)
			(layer "F.Fab")
		)
		(fp_line
			(start 0.67945 0.3048)
			(end 0.120396 0.3048)
			(stroke
				(width 0.1)
				(type default)
			)
			(layer "F.Fab")
		)
		(fp_line
			(start -0.12065 0.2794)
			(end -0.12065 0.3048)
			(stroke
				(width 0.1)
				(type default)
			)
			(layer "F.Fab")
		)
		(fp_line
			(start 0.120396 0.2794)
			(end -0.12065 0.2794)
			(stroke
				(width 0.1)
				(type default)
			)
			(layer "F.Fab")
		)
		(fp_line
			(start -0.12065 -0.2794)
			(end 0.12065 -0.2794)
			(stroke
				(width 0.1)
				(type default)
			)
			(layer "F.Fab")
		)
		(fp_line
			(start 0.12065 -0.2794)
			(end 0.12065 -0.3048)
			(stroke
				(width 0.1)
				(type default)
			)
			(layer "F.Fab")
		)
		(fp_line
			(start 0.12065 -0.3048)
			(end 0.67945 -0.3048)
			(stroke
				(width 0.1)
				(type default)
			)
			(layer "F.Fab")
		)
		(fp_line
			(start 0.67945 -0.3048)
			(end 0.67945 0.3048)
			(stroke
				(width 0.1)
				(type default)
			)
			(layer "F.Fab")
		)
		(fp_line
			(start -0.67945 -0.305054)
			(end -0.12065 -0.305054)
			(stroke
				(width 0.1)
				(type default)
			)
			(layer "F.Fab")
		)
		(fp_line
			(start -0.12065 -0.305054)
			(end -0.12065 -0.2794)
			(stroke
				(width 0.1)
				(type default)
			)
			(layer "F.Fab")
		)
		(pad "1" smd circle
			(at -0.40005 0 270)
			(size 0 0)
			(layers "F.Cu" "F.Mask" "F.Paste")
			(net "PVDD11_S3_P1")
		)
		(pad "2" smd circle
			(at 0.40005 0 270)
			(size 0 0)
			(layers "F.Cu" "F.Mask" "F.Paste")
			(net "GND")
		)
	)
)
